FILE_TYPE=LIBRARY_PARTS;
primitive 'CONN160_10131762101LF';
  pin
    'A8':
      PIN_NUMBER='(A8,0)';
      BIDIRECTIONAL='TRUE';
      INPUT_LOAD='(-0.01,0.01)';
      OUTPUT_LOAD='(1.0,-1.0)';
    'A7':
      PIN_NUMBER='(A7,0)';
      BIDIRECTIONAL='TRUE';
      INPUT_LOAD='(-0.01,0.01)';
      OUTPUT_LOAD='(1.0,-1.0)';
    'A6':
      PIN_NUMBER='(A6,0)';
      BIDIRECTIONAL='TRUE';
      INPUT_LOAD='(-0.01,0.01)';
      OUTPUT_LOAD='(1.0,-1.0)';
    'A5':
      PIN_NUMBER='(A5,0)';
      BIDIRECTIONAL='TRUE';
      INPUT_LOAD='(-0.01,0.01)';
      OUTPUT_LOAD='(1.0,-1.0)';
    'B8':
      PIN_NUMBER='(B8,0)';
      BIDIRECTIONAL='TRUE';
      INPUT_LOAD='(-0.01,0.01)';
      OUTPUT_LOAD='(1.0,-1.0)';
    'B7':
      PIN_NUMBER='(B7,0)';
      BIDIRECTIONAL='TRUE';
      INPUT_LOAD='(-0.01,0.01)';
      OUTPUT_LOAD='(1.0,-1.0)';
    'B6':
      PIN_NUMBER='(B6,0)';
      BIDIRECTIONAL='TRUE';
      INPUT_LOAD='(-0.01,0.01)';
      OUTPUT_LOAD='(1.0,-1.0)';
    'B5':
      PIN_NUMBER='(B5,0)';
      BIDIRECTIONAL='TRUE';
      INPUT_LOAD='(-0.01,0.01)';
      OUTPUT_LOAD='(1.0,-1.0)';
    'C8':
      PIN_NUMBER='(C8,0)';
      BIDIRECTIONAL='TRUE';
      INPUT_LOAD='(-0.01,0.01)';
      OUTPUT_LOAD='(1.0,-1.0)';
    'C7':
      PIN_NUMBER='(C7,0)';
      BIDIRECTIONAL='TRUE';
      INPUT_LOAD='(-0.01,0.01)';
      OUTPUT_LOAD='(1.0,-1.0)';
    'C6':
      PIN_NUMBER='(C6,0)';
      BIDIRECTIONAL='TRUE';
      INPUT_LOAD='(-0.01,0.01)';
      OUTPUT_LOAD='(1.0,-1.0)';
    'C5':
      PIN_NUMBER='(C5,0)';
      BIDIRECTIONAL='TRUE';
      INPUT_LOAD='(-0.01,0.01)';
      OUTPUT_LOAD='(1.0,-1.0)';
    'D8':
      PIN_NUMBER='(D8,0)';
      BIDIRECTIONAL='TRUE';
      INPUT_LOAD='(-0.01,0.01)';
      OUTPUT_LOAD='(1.0,-1.0)';
    'D7':
      PIN_NUMBER='(D7,0)';
      BIDIRECTIONAL='TRUE';
      INPUT_LOAD='(-0.01,0.01)';
      OUTPUT_LOAD='(1.0,-1.0)';
    'D6':
      PIN_NUMBER='(D6,0)';
      BIDIRECTIONAL='TRUE';
      INPUT_LOAD='(-0.01,0.01)';
      OUTPUT_LOAD='(1.0,-1.0)';
    'D5':
      PIN_NUMBER='(D5,0)';
      BIDIRECTIONAL='TRUE';
      INPUT_LOAD='(-0.01,0.01)';
      OUTPUT_LOAD='(1.0,-1.0)';
    'E8':
      PIN_NUMBER='(E8,0)';
      BIDIRECTIONAL='TRUE';
      INPUT_LOAD='(-0.01,0.01)';
      OUTPUT_LOAD='(1.0,-1.0)';
    'E7':
      PIN_NUMBER='(E7,0)';
      BIDIRECTIONAL='TRUE';
      INPUT_LOAD='(-0.01,0.01)';
      OUTPUT_LOAD='(1.0,-1.0)';
    'E6':
      PIN_NUMBER='(E6,0)';
      BIDIRECTIONAL='TRUE';
      INPUT_LOAD='(-0.01,0.01)';
      OUTPUT_LOAD='(1.0,-1.0)';
    'E5':
      PIN_NUMBER='(E5,0)';
      BIDIRECTIONAL='TRUE';
      INPUT_LOAD='(-0.01,0.01)';
      OUTPUT_LOAD='(1.0,-1.0)';
    'F8':
      PIN_NUMBER='(F8,0)';
      BIDIRECTIONAL='TRUE';
      INPUT_LOAD='(-0.01,0.01)';
      OUTPUT_LOAD='(1.0,-1.0)';
    'F7':
      PIN_NUMBER='(F7,0)';
      BIDIRECTIONAL='TRUE';
      INPUT_LOAD='(-0.01,0.01)';
      OUTPUT_LOAD='(1.0,-1.0)';
    'F6':
      PIN_NUMBER='(F6,0)';
      BIDIRECTIONAL='TRUE';
      INPUT_LOAD='(-0.01,0.01)';
      OUTPUT_LOAD='(1.0,-1.0)';
    'F5':
      PIN_NUMBER='(F5,0)';
      BIDIRECTIONAL='TRUE';
      INPUT_LOAD='(-0.01,0.01)';
      OUTPUT_LOAD='(1.0,-1.0)';
    'G8':
      PIN_NUMBER='(G8,0)';
      BIDIRECTIONAL='TRUE';
      INPUT_LOAD='(-0.01,0.01)';
      OUTPUT_LOAD='(1.0,-1.0)';
    'G7':
      PIN_NUMBER='(G7,0)';
      BIDIRECTIONAL='TRUE';
      INPUT_LOAD='(-0.01,0.01)';
      OUTPUT_LOAD='(1.0,-1.0)';
    'G6':
      PIN_NUMBER='(G6,0)';
      BIDIRECTIONAL='TRUE';
      INPUT_LOAD='(-0.01,0.01)';
      OUTPUT_LOAD='(1.0,-1.0)';
    'G5':
      PIN_NUMBER='(G5,0)';
      BIDIRECTIONAL='TRUE';
      INPUT_LOAD='(-0.01,0.01)';
      OUTPUT_LOAD='(1.0,-1.0)';
    'H8':
      PIN_NUMBER='(H8,0)';
      BIDIRECTIONAL='TRUE';
      INPUT_LOAD='(-0.01,0.01)';
      OUTPUT_LOAD='(1.0,-1.0)';
    'H7':
      PIN_NUMBER='(H7,0)';
      BIDIRECTIONAL='TRUE';
      INPUT_LOAD='(-0.01,0.01)';
      OUTPUT_LOAD='(1.0,-1.0)';
    'H6':
      PIN_NUMBER='(H6,0)';
      BIDIRECTIONAL='TRUE';
      INPUT_LOAD='(-0.01,0.01)';
      OUTPUT_LOAD='(1.0,-1.0)';
    'H5':
      PIN_NUMBER='(H5,0)';
      BIDIRECTIONAL='TRUE';
      INPUT_LOAD='(-0.01,0.01)';
      OUTPUT_LOAD='(1.0,-1.0)';
    'I8':
      PIN_NUMBER='(I8,0)';
      BIDIRECTIONAL='TRUE';
      INPUT_LOAD='(-0.01,0.01)';
      OUTPUT_LOAD='(1.0,-1.0)';
    'I7':
      PIN_NUMBER='(I7,0)';
      BIDIRECTIONAL='TRUE';
      INPUT_LOAD='(-0.01,0.01)';
      OUTPUT_LOAD='(1.0,-1.0)';
    'I6':
      PIN_NUMBER='(I6,0)';
      BIDIRECTIONAL='TRUE';
      INPUT_LOAD='(-0.01,0.01)';
      OUTPUT_LOAD='(1.0,-1.0)';
    'I5':
      PIN_NUMBER='(I5,0)';
      BIDIRECTIONAL='TRUE';
      INPUT_LOAD='(-0.01,0.01)';
      OUTPUT_LOAD='(1.0,-1.0)';
    'J8':
      PIN_NUMBER='(J8,0)';
      BIDIRECTIONAL='TRUE';
      INPUT_LOAD='(-0.01,0.01)';
      OUTPUT_LOAD='(1.0,-1.0)';
    'J7':
      PIN_NUMBER='(J7,0)';
      BIDIRECTIONAL='TRUE';
      INPUT_LOAD='(-0.01,0.01)';
      OUTPUT_LOAD='(1.0,-1.0)';
    'J6':
      PIN_NUMBER='(J6,0)';
      BIDIRECTIONAL='TRUE';
      INPUT_LOAD='(-0.01,0.01)';
      OUTPUT_LOAD='(1.0,-1.0)';
    'J5':
      PIN_NUMBER='(J5,0)';
      BIDIRECTIONAL='TRUE';
      INPUT_LOAD='(-0.01,0.01)';
      OUTPUT_LOAD='(1.0,-1.0)';
    'K8':
      PIN_NUMBER='(K8,0)';
      BIDIRECTIONAL='TRUE';
      INPUT_LOAD='(-0.01,0.01)';
      OUTPUT_LOAD='(1.0,-1.0)';
    'K7':
      PIN_NUMBER='(K7,0)';
      BIDIRECTIONAL='TRUE';
      INPUT_LOAD='(-0.01,0.01)';
      OUTPUT_LOAD='(1.0,-1.0)';
    'K6':
      PIN_NUMBER='(K6,0)';
      BIDIRECTIONAL='TRUE';
      INPUT_LOAD='(-0.01,0.01)';
      OUTPUT_LOAD='(1.0,-1.0)';
    'K5':
      PIN_NUMBER='(K5,0)';
      BIDIRECTIONAL='TRUE';
      INPUT_LOAD='(-0.01,0.01)';
      OUTPUT_LOAD='(1.0,-1.0)';
    'L8':
      PIN_NUMBER='(L8,0)';
      BIDIRECTIONAL='TRUE';
      INPUT_LOAD='(-0.01,0.01)';
      OUTPUT_LOAD='(1.0,-1.0)';
    'L7':
      PIN_NUMBER='(L7,0)';
      BIDIRECTIONAL='TRUE';
      INPUT_LOAD='(-0.01,0.01)';
      OUTPUT_LOAD='(1.0,-1.0)';
    'L6':
      PIN_NUMBER='(L6,0)';
      BIDIRECTIONAL='TRUE';
      INPUT_LOAD='(-0.01,0.01)';
      OUTPUT_LOAD='(1.0,-1.0)';
    'L5':
      PIN_NUMBER='(L5,0)';
      BIDIRECTIONAL='TRUE';
      INPUT_LOAD='(-0.01,0.01)';
      OUTPUT_LOAD='(1.0,-1.0)';
    'M5':
      PIN_NUMBER='(M5,0)';
      BIDIRECTIONAL='TRUE';
      INPUT_LOAD='(-0.01,0.01)';
      OUTPUT_LOAD='(1.0,-1.0)';
    'N5':
      PIN_NUMBER='(N5,0)';
      BIDIRECTIONAL='TRUE';
      INPUT_LOAD='(-0.01,0.01)';
      OUTPUT_LOAD='(1.0,-1.0)';
    'M6':
      PIN_NUMBER='(M6,0)';
      BIDIRECTIONAL='TRUE';
      INPUT_LOAD='(-0.01,0.01)';
      OUTPUT_LOAD='(1.0,-1.0)';
    'N6':
      PIN_NUMBER='(N6,0)';
      BIDIRECTIONAL='TRUE';
      INPUT_LOAD='(-0.01,0.01)';
      OUTPUT_LOAD='(1.0,-1.0)';
    'M7':
      PIN_NUMBER='(M7,0)';
      BIDIRECTIONAL='TRUE';
      INPUT_LOAD='(-0.01,0.01)';
      OUTPUT_LOAD='(1.0,-1.0)';
    'N7':
      PIN_NUMBER='(N7,0)';
      BIDIRECTIONAL='TRUE';
      INPUT_LOAD='(-0.01,0.01)';
      OUTPUT_LOAD='(1.0,-1.0)';
    'M8':
      PIN_NUMBER='(M8,0)';
      BIDIRECTIONAL='TRUE';
      INPUT_LOAD='(-0.01,0.01)';
      OUTPUT_LOAD='(1.0,-1.0)';
    'N8':
      PIN_NUMBER='(N8,0)';
      BIDIRECTIONAL='TRUE';
      INPUT_LOAD='(-0.01,0.01)';
      OUTPUT_LOAD='(1.0,-1.0)';
    'O5':
      PIN_NUMBER='(O5,0)';
      BIDIRECTIONAL='TRUE';
      INPUT_LOAD='(-0.01,0.01)';
      OUTPUT_LOAD='(1.0,-1.0)';
    'P5':
      PIN_NUMBER='(P5,0)';
      BIDIRECTIONAL='TRUE';
      INPUT_LOAD='(-0.01,0.01)';
      OUTPUT_LOAD='(1.0,-1.0)';
    'Q5':
      PIN_NUMBER='(Q5,0)';
      BIDIRECTIONAL='TRUE';
      INPUT_LOAD='(-0.01,0.01)';
      OUTPUT_LOAD='(1.0,-1.0)';
    'R5':
      PIN_NUMBER='(R5,0)';
      BIDIRECTIONAL='TRUE';
      INPUT_LOAD='(-0.01,0.01)';
      OUTPUT_LOAD='(1.0,-1.0)';
    'S5':
      PIN_NUMBER='(S5,0)';
      BIDIRECTIONAL='TRUE';
      INPUT_LOAD='(-0.01,0.01)';
      OUTPUT_LOAD='(1.0,-1.0)';
    'T5':
      PIN_NUMBER='(T5,0)';
      BIDIRECTIONAL='TRUE';
      INPUT_LOAD='(-0.01,0.01)';
      OUTPUT_LOAD='(1.0,-1.0)';
    'O6':
      PIN_NUMBER='(O6,0)';
      BIDIRECTIONAL='TRUE';
      INPUT_LOAD='(-0.01,0.01)';
      OUTPUT_LOAD='(1.0,-1.0)';
    'P6':
      PIN_NUMBER='(P6,0)';
      BIDIRECTIONAL='TRUE';
      INPUT_LOAD='(-0.01,0.01)';
      OUTPUT_LOAD='(1.0,-1.0)';
    'Q6':
      PIN_NUMBER='(Q6,0)';
      BIDIRECTIONAL='TRUE';
      INPUT_LOAD='(-0.01,0.01)';
      OUTPUT_LOAD='(1.0,-1.0)';
    'R6':
      PIN_NUMBER='(R6,0)';
      BIDIRECTIONAL='TRUE';
      INPUT_LOAD='(-0.01,0.01)';
      OUTPUT_LOAD='(1.0,-1.0)';
    'S6':
      PIN_NUMBER='(S6,0)';
      BIDIRECTIONAL='TRUE';
      INPUT_LOAD='(-0.01,0.01)';
      OUTPUT_LOAD='(1.0,-1.0)';
    'T6':
      PIN_NUMBER='(T6,0)';
      BIDIRECTIONAL='TRUE';
      INPUT_LOAD='(-0.01,0.01)';
      OUTPUT_LOAD='(1.0,-1.0)';
    'O7':
      PIN_NUMBER='(O7,0)';
      BIDIRECTIONAL='TRUE';
      INPUT_LOAD='(-0.01,0.01)';
      OUTPUT_LOAD='(1.0,-1.0)';
    'P7':
      PIN_NUMBER='(P7,0)';
      BIDIRECTIONAL='TRUE';
      INPUT_LOAD='(-0.01,0.01)';
      OUTPUT_LOAD='(1.0,-1.0)';
    'Q7':
      PIN_NUMBER='(Q7,0)';
      BIDIRECTIONAL='TRUE';
      INPUT_LOAD='(-0.01,0.01)';
      OUTPUT_LOAD='(1.0,-1.0)';
    'R7':
      PIN_NUMBER='(R7,0)';
      BIDIRECTIONAL='TRUE';
      INPUT_LOAD='(-0.01,0.01)';
      OUTPUT_LOAD='(1.0,-1.0)';
    'S7':
      PIN_NUMBER='(S7,0)';
      BIDIRECTIONAL='TRUE';
      INPUT_LOAD='(-0.01,0.01)';
      OUTPUT_LOAD='(1.0,-1.0)';
    'T7':
      PIN_NUMBER='(T7,0)';
      BIDIRECTIONAL='TRUE';
      INPUT_LOAD='(-0.01,0.01)';
      OUTPUT_LOAD='(1.0,-1.0)';
    'O8':
      PIN_NUMBER='(O8,0)';
      BIDIRECTIONAL='TRUE';
      INPUT_LOAD='(-0.01,0.01)';
      OUTPUT_LOAD='(1.0,-1.0)';
    'P8':
      PIN_NUMBER='(P8,0)';
      BIDIRECTIONAL='TRUE';
      INPUT_LOAD='(-0.01,0.01)';
      OUTPUT_LOAD='(1.0,-1.0)';
    'Q8':
      PIN_NUMBER='(Q8,0)';
      BIDIRECTIONAL='TRUE';
      INPUT_LOAD='(-0.01,0.01)';
      OUTPUT_LOAD='(1.0,-1.0)';
    'R8':
      PIN_NUMBER='(R8,0)';
      BIDIRECTIONAL='TRUE';
      INPUT_LOAD='(-0.01,0.01)';
      OUTPUT_LOAD='(1.0,-1.0)';
    'S8':
      PIN_NUMBER='(S8,0)';
      BIDIRECTIONAL='TRUE';
      INPUT_LOAD='(-0.01,0.01)';
      OUTPUT_LOAD='(1.0,-1.0)';
    'T8':
      PIN_NUMBER='(T8,0)';
      BIDIRECTIONAL='TRUE';
      INPUT_LOAD='(-0.01,0.01)';
      OUTPUT_LOAD='(1.0,-1.0)';
    'A4':
      PIN_NUMBER='(0,A4)';
      BIDIRECTIONAL='TRUE';
      INPUT_LOAD='(-0.01,0.01)';
      OUTPUT_LOAD='(1.0,-1.0)';
    'A3':
      PIN_NUMBER='(0,A3)';
      BIDIRECTIONAL='TRUE';
      INPUT_LOAD='(-0.01,0.01)';
      OUTPUT_LOAD='(1.0,-1.0)';
    'A2':
      PIN_NUMBER='(0,A2)';
      BIDIRECTIONAL='TRUE';
      INPUT_LOAD='(-0.01,0.01)';
      OUTPUT_LOAD='(1.0,-1.0)';
    'A1':
      PIN_NUMBER='(0,A1)';
      BIDIRECTIONAL='TRUE';
      INPUT_LOAD='(-0.01,0.01)';
      OUTPUT_LOAD='(1.0,-1.0)';
    'B4':
      PIN_NUMBER='(0,B4)';
      BIDIRECTIONAL='TRUE';
      INPUT_LOAD='(-0.01,0.01)';
      OUTPUT_LOAD='(1.0,-1.0)';
    'B3':
      PIN_NUMBER='(0,B3)';
      BIDIRECTIONAL='TRUE';
      INPUT_LOAD='(-0.01,0.01)';
      OUTPUT_LOAD='(1.0,-1.0)';
    'B2':
      PIN_NUMBER='(0,B2)';
      BIDIRECTIONAL='TRUE';
      INPUT_LOAD='(-0.01,0.01)';
      OUTPUT_LOAD='(1.0,-1.0)';
    'B1':
      PIN_NUMBER='(0,B1)';
      BIDIRECTIONAL='TRUE';
      INPUT_LOAD='(-0.01,0.01)';
      OUTPUT_LOAD='(1.0,-1.0)';
    'C4':
      PIN_NUMBER='(0,C4)';
      BIDIRECTIONAL='TRUE';
      INPUT_LOAD='(-0.01,0.01)';
      OUTPUT_LOAD='(1.0,-1.0)';
    'C3':
      PIN_NUMBER='(0,C3)';
      BIDIRECTIONAL='TRUE';
      INPUT_LOAD='(-0.01,0.01)';
      OUTPUT_LOAD='(1.0,-1.0)';
    'C2':
      PIN_NUMBER='(0,C2)';
      BIDIRECTIONAL='TRUE';
      INPUT_LOAD='(-0.01,0.01)';
      OUTPUT_LOAD='(1.0,-1.0)';
    'C1':
      PIN_NUMBER='(0,C1)';
      BIDIRECTIONAL='TRUE';
      INPUT_LOAD='(-0.01,0.01)';
      OUTPUT_LOAD='(1.0,-1.0)';
    'D4':
      PIN_NUMBER='(0,D4)';
      BIDIRECTIONAL='TRUE';
      INPUT_LOAD='(-0.01,0.01)';
      OUTPUT_LOAD='(1.0,-1.0)';
    'D3':
      PIN_NUMBER='(0,D3)';
      BIDIRECTIONAL='TRUE';
      INPUT_LOAD='(-0.01,0.01)';
      OUTPUT_LOAD='(1.0,-1.0)';
    'D2':
      PIN_NUMBER='(0,D2)';
      BIDIRECTIONAL='TRUE';
      INPUT_LOAD='(-0.01,0.01)';
      OUTPUT_LOAD='(1.0,-1.0)';
    'D1':
      PIN_NUMBER='(0,D1)';
      BIDIRECTIONAL='TRUE';
      INPUT_LOAD='(-0.01,0.01)';
      OUTPUT_LOAD='(1.0,-1.0)';
    'E4':
      PIN_NUMBER='(0,E4)';
      BIDIRECTIONAL='TRUE';
      INPUT_LOAD='(-0.01,0.01)';
      OUTPUT_LOAD='(1.0,-1.0)';
    'E3':
      PIN_NUMBER='(0,E3)';
      BIDIRECTIONAL='TRUE';
      INPUT_LOAD='(-0.01,0.01)';
      OUTPUT_LOAD='(1.0,-1.0)';
    'E2':
      PIN_NUMBER='(0,E2)';
      BIDIRECTIONAL='TRUE';
      INPUT_LOAD='(-0.01,0.01)';
      OUTPUT_LOAD='(1.0,-1.0)';
    'E1':
      PIN_NUMBER='(0,E1)';
      BIDIRECTIONAL='TRUE';
      INPUT_LOAD='(-0.01,0.01)';
      OUTPUT_LOAD='(1.0,-1.0)';
    'F4':
      PIN_NUMBER='(0,F4)';
      BIDIRECTIONAL='TRUE';
      INPUT_LOAD='(-0.01,0.01)';
      OUTPUT_LOAD='(1.0,-1.0)';
    'F3':
      PIN_NUMBER='(0,F3)';
      BIDIRECTIONAL='TRUE';
      INPUT_LOAD='(-0.01,0.01)';
      OUTPUT_LOAD='(1.0,-1.0)';
    'F2':
      PIN_NUMBER='(0,F2)';
      BIDIRECTIONAL='TRUE';
      INPUT_LOAD='(-0.01,0.01)';
      OUTPUT_LOAD='(1.0,-1.0)';
    'F1':
      PIN_NUMBER='(0,F1)';
      BIDIRECTIONAL='TRUE';
      INPUT_LOAD='(-0.01,0.01)';
      OUTPUT_LOAD='(1.0,-1.0)';
    'G4':
      PIN_NUMBER='(0,G4)';
      BIDIRECTIONAL='TRUE';
      INPUT_LOAD='(-0.01,0.01)';
      OUTPUT_LOAD='(1.0,-1.0)';
    'G3':
      PIN_NUMBER='(0,G3)';
      BIDIRECTIONAL='TRUE';
      INPUT_LOAD='(-0.01,0.01)';
      OUTPUT_LOAD='(1.0,-1.0)';
    'G2':
      PIN_NUMBER='(0,G2)';
      BIDIRECTIONAL='TRUE';
      INPUT_LOAD='(-0.01,0.01)';
      OUTPUT_LOAD='(1.0,-1.0)';
    'G1':
      PIN_NUMBER='(0,G1)';
      BIDIRECTIONAL='TRUE';
      INPUT_LOAD='(-0.01,0.01)';
      OUTPUT_LOAD='(1.0,-1.0)';
    'H4':
      PIN_NUMBER='(0,H4)';
      BIDIRECTIONAL='TRUE';
      INPUT_LOAD='(-0.01,0.01)';
      OUTPUT_LOAD='(1.0,-1.0)';
    'H3':
      PIN_NUMBER='(0,H3)';
      BIDIRECTIONAL='TRUE';
      INPUT_LOAD='(-0.01,0.01)';
      OUTPUT_LOAD='(1.0,-1.0)';
    'H2':
      PIN_NUMBER='(0,H2)';
      BIDIRECTIONAL='TRUE';
      INPUT_LOAD='(-0.01,0.01)';
      OUTPUT_LOAD='(1.0,-1.0)';
    'H1':
      PIN_NUMBER='(0,H1)';
      BIDIRECTIONAL='TRUE';
      INPUT_LOAD='(-0.01,0.01)';
      OUTPUT_LOAD='(1.0,-1.0)';
    'I4':
      PIN_NUMBER='(0,I4)';
      BIDIRECTIONAL='TRUE';
      INPUT_LOAD='(-0.01,0.01)';
      OUTPUT_LOAD='(1.0,-1.0)';
    'I3':
      PIN_NUMBER='(0,I3)';
      BIDIRECTIONAL='TRUE';
      INPUT_LOAD='(-0.01,0.01)';
      OUTPUT_LOAD='(1.0,-1.0)';
    'I2':
      PIN_NUMBER='(0,I2)';
      BIDIRECTIONAL='TRUE';
      INPUT_LOAD='(-0.01,0.01)';
      OUTPUT_LOAD='(1.0,-1.0)';
    'I1':
      PIN_NUMBER='(0,I1)';
      BIDIRECTIONAL='TRUE';
      INPUT_LOAD='(-0.01,0.01)';
      OUTPUT_LOAD='(1.0,-1.0)';
    'J4':
      PIN_NUMBER='(0,J4)';
      BIDIRECTIONAL='TRUE';
      INPUT_LOAD='(-0.01,0.01)';
      OUTPUT_LOAD='(1.0,-1.0)';
    'J3':
      PIN_NUMBER='(0,J3)';
      BIDIRECTIONAL='TRUE';
      INPUT_LOAD='(-0.01,0.01)';
      OUTPUT_LOAD='(1.0,-1.0)';
    'J2':
      PIN_NUMBER='(0,J2)';
      BIDIRECTIONAL='TRUE';
      INPUT_LOAD='(-0.01,0.01)';
      OUTPUT_LOAD='(1.0,-1.0)';
    'J1':
      PIN_NUMBER='(0,J1)';
      BIDIRECTIONAL='TRUE';
      INPUT_LOAD='(-0.01,0.01)';
      OUTPUT_LOAD='(1.0,-1.0)';
    'K4':
      PIN_NUMBER='(0,K4)';
      BIDIRECTIONAL='TRUE';
      INPUT_LOAD='(-0.01,0.01)';
      OUTPUT_LOAD='(1.0,-1.0)';
    'K3':
      PIN_NUMBER='(0,K3)';
      BIDIRECTIONAL='TRUE';
      INPUT_LOAD='(-0.01,0.01)';
      OUTPUT_LOAD='(1.0,-1.0)';
    'K2':
      PIN_NUMBER='(0,K2)';
      BIDIRECTIONAL='TRUE';
      INPUT_LOAD='(-0.01,0.01)';
      OUTPUT_LOAD='(1.0,-1.0)';
    'K1':
      PIN_NUMBER='(0,K1)';
      BIDIRECTIONAL='TRUE';
      INPUT_LOAD='(-0.01,0.01)';
      OUTPUT_LOAD='(1.0,-1.0)';
    'L4':
      PIN_NUMBER='(0,L4)';
      BIDIRECTIONAL='TRUE';
      INPUT_LOAD='(-0.01,0.01)';
      OUTPUT_LOAD='(1.0,-1.0)';
    'L3':
      PIN_NUMBER='(0,L3)';
      BIDIRECTIONAL='TRUE';
      INPUT_LOAD='(-0.01,0.01)';
      OUTPUT_LOAD='(1.0,-1.0)';
    'L2':
      PIN_NUMBER='(0,L2)';
      BIDIRECTIONAL='TRUE';
      INPUT_LOAD='(-0.01,0.01)';
      OUTPUT_LOAD='(1.0,-1.0)';
    'L1':
      PIN_NUMBER='(0,L1)';
      BIDIRECTIONAL='TRUE';
      INPUT_LOAD='(-0.01,0.01)';
      OUTPUT_LOAD='(1.0,-1.0)';
    'M1':
      PIN_NUMBER='(0,M1)';
      BIDIRECTIONAL='TRUE';
      INPUT_LOAD='(-0.01,0.01)';
      OUTPUT_LOAD='(1.0,-1.0)';
    'N1':
      PIN_NUMBER='(0,N1)';
      BIDIRECTIONAL='TRUE';
      INPUT_LOAD='(-0.01,0.01)';
      OUTPUT_LOAD='(1.0,-1.0)';
    'M2':
      PIN_NUMBER='(0,M2)';
      BIDIRECTIONAL='TRUE';
      INPUT_LOAD='(-0.01,0.01)';
      OUTPUT_LOAD='(1.0,-1.0)';
    'N2':
      PIN_NUMBER='(0,N2)';
      BIDIRECTIONAL='TRUE';
      INPUT_LOAD='(-0.01,0.01)';
      OUTPUT_LOAD='(1.0,-1.0)';
    'M3':
      PIN_NUMBER='(0,M3)';
      BIDIRECTIONAL='TRUE';
      INPUT_LOAD='(-0.01,0.01)';
      OUTPUT_LOAD='(1.0,-1.0)';
    'N3':
      PIN_NUMBER='(0,N3)';
      BIDIRECTIONAL='TRUE';
      INPUT_LOAD='(-0.01,0.01)';
      OUTPUT_LOAD='(1.0,-1.0)';
    'M4':
      PIN_NUMBER='(0,M4)';
      BIDIRECTIONAL='TRUE';
      INPUT_LOAD='(-0.01,0.01)';
      OUTPUT_LOAD='(1.0,-1.0)';
    'N4':
      PIN_NUMBER='(0,N4)';
      BIDIRECTIONAL='TRUE';
      INPUT_LOAD='(-0.01,0.01)';
      OUTPUT_LOAD='(1.0,-1.0)';
    'O1':
      PIN_NUMBER='(0,O1)';
      BIDIRECTIONAL='TRUE';
      INPUT_LOAD='(-0.01,0.01)';
      OUTPUT_LOAD='(1.0,-1.0)';
    'P1':
      PIN_NUMBER='(0,P1)';
      BIDIRECTIONAL='TRUE';
      INPUT_LOAD='(-0.01,0.01)';
      OUTPUT_LOAD='(1.0,-1.0)';
    'Q1':
      PIN_NUMBER='(0,Q1)';
      BIDIRECTIONAL='TRUE';
      INPUT_LOAD='(-0.01,0.01)';
      OUTPUT_LOAD='(1.0,-1.0)';
    'R1':
      PIN_NUMBER='(0,R1)';
      BIDIRECTIONAL='TRUE';
      INPUT_LOAD='(-0.01,0.01)';
      OUTPUT_LOAD='(1.0,-1.0)';
    'S1':
      PIN_NUMBER='(0,S1)';
      BIDIRECTIONAL='TRUE';
      INPUT_LOAD='(-0.01,0.01)';
      OUTPUT_LOAD='(1.0,-1.0)';
    'T1':
      PIN_NUMBER='(0,T1)';
      BIDIRECTIONAL='TRUE';
      INPUT_LOAD='(-0.01,0.01)';
      OUTPUT_LOAD='(1.0,-1.0)';
    'O2':
      PIN_NUMBER='(0,O2)';
      BIDIRECTIONAL='TRUE';
      INPUT_LOAD='(-0.01,0.01)';
      OUTPUT_LOAD='(1.0,-1.0)';
    'P2':
      PIN_NUMBER='(0,P2)';
      BIDIRECTIONAL='TRUE';
      INPUT_LOAD='(-0.01,0.01)';
      OUTPUT_LOAD='(1.0,-1.0)';
    'Q2':
      PIN_NUMBER='(0,Q2)';
      BIDIRECTIONAL='TRUE';
      INPUT_LOAD='(-0.01,0.01)';
      OUTPUT_LOAD='(1.0,-1.0)';
    'R2':
      PIN_NUMBER='(0,R2)';
      BIDIRECTIONAL='TRUE';
      INPUT_LOAD='(-0.01,0.01)';
      OUTPUT_LOAD='(1.0,-1.0)';
    'S2':
      PIN_NUMBER='(0,S2)';
      BIDIRECTIONAL='TRUE';
      INPUT_LOAD='(-0.01,0.01)';
      OUTPUT_LOAD='(1.0,-1.0)';
    'T2':
      PIN_NUMBER='(0,T2)';
      BIDIRECTIONAL='TRUE';
      INPUT_LOAD='(-0.01,0.01)';
      OUTPUT_LOAD='(1.0,-1.0)';
    'O3':
      PIN_NUMBER='(0,O3)';
      BIDIRECTIONAL='TRUE';
      INPUT_LOAD='(-0.01,0.01)';
      OUTPUT_LOAD='(1.0,-1.0)';
    'P3':
      PIN_NUMBER='(0,P3)';
      BIDIRECTIONAL='TRUE';
      INPUT_LOAD='(-0.01,0.01)';
      OUTPUT_LOAD='(1.0,-1.0)';
    'Q3':
      PIN_NUMBER='(0,Q3)';
      BIDIRECTIONAL='TRUE';
      INPUT_LOAD='(-0.01,0.01)';
      OUTPUT_LOAD='(1.0,-1.0)';
    'R3':
      PIN_NUMBER='(0,R3)';
      BIDIRECTIONAL='TRUE';
      INPUT_LOAD='(-0.01,0.01)';
      OUTPUT_LOAD='(1.0,-1.0)';
    'S3':
      PIN_NUMBER='(0,S3)';
      BIDIRECTIONAL='TRUE';
      INPUT_LOAD='(-0.01,0.01)';
      OUTPUT_LOAD='(1.0,-1.0)';
    'T3':
      PIN_NUMBER='(0,T3)';
      BIDIRECTIONAL='TRUE';
      INPUT_LOAD='(-0.01,0.01)';
      OUTPUT_LOAD='(1.0,-1.0)';
    'O4':
      PIN_NUMBER='(0,O4)';
      BIDIRECTIONAL='TRUE';
      INPUT_LOAD='(-0.01,0.01)';
      OUTPUT_LOAD='(1.0,-1.0)';
    'P4':
      PIN_NUMBER='(0,P4)';
      BIDIRECTIONAL='TRUE';
      INPUT_LOAD='(-0.01,0.01)';
      OUTPUT_LOAD='(1.0,-1.0)';
    'Q4':
      PIN_NUMBER='(0,Q4)';
      BIDIRECTIONAL='TRUE';
      INPUT_LOAD='(-0.01,0.01)';
      OUTPUT_LOAD='(1.0,-1.0)';
    'R4':
      PIN_NUMBER='(0,R4)';
      BIDIRECTIONAL='TRUE';
      INPUT_LOAD='(-0.01,0.01)';
      OUTPUT_LOAD='(1.0,-1.0)';
    'S4':
      PIN_NUMBER='(0,S4)';
      BIDIRECTIONAL='TRUE';
      INPUT_LOAD='(-0.01,0.01)';
      OUTPUT_LOAD='(1.0,-1.0)';
    'T4':
      PIN_NUMBER='(0,T4)';
      BIDIRECTIONAL='TRUE';
      INPUT_LOAD='(-0.01,0.01)';
      OUTPUT_LOAD='(1.0,-1.0)';
  end_pin;
  body
    PART_NAME='CONN160_10131762101LF';
    BODY_NAME='CONN160_10131762101LF';
    PHYS_DES_PREFIX='J';
    CLASS='IO';
  end_body;
end_primitive;

END.
